(kicad_pcb
	(version 20260206)
	(generator "pcbnew")
	(generator_version "10.0")
	(general
		(thickness 1.6)
		(legacy_teardrops no)
	)
	(paper "A4")
	(title_block
		(title "v1-chassis-manager — T6M_CM_d_v01_1031_1645.brd")
		(comment 1 "Open CloudServer (Microsoft) / footprints 1993-2002 of 2512")
	)
	(layers
		(0 "F.Cu" signal "TOP")
		(4 "In1.Cu" signal "GND1")
		(6 "In2.Cu" signal "IN1")
		(8 "In3.Cu" signal "VCC1")
		(10 "In4.Cu" signal "VCC2")
		(12 "In5.Cu" signal "GND2")
		(14 "In6.Cu" signal "IN2")
		(16 "In7.Cu" signal "IN3")
		(18 "In8.Cu" signal "GND3")
		(2 "B.Cu" signal "BOTTOM")
		(9 "F.Adhes" user "F.Adhesive")
		(11 "B.Adhes" user "B.Adhesive")
		(13 "F.Paste" user "Package Geometry/Pastemask Top")
		(15 "B.Paste" user "Package Geometry/Pastemask Bottom")
		(5 "F.SilkS" user "Ref Des/Silkscreen Top")
		(7 "B.SilkS" user "Ref Des/Silkscreen Bottom")
		(1 "F.Mask" user "Board Geometry/Soldermask Top")
		(3 "B.Mask" user "Board Geometry/Soldermask Bottom")
		(17 "Dwgs.User" user "User.Drawings")
		(19 "Cmts.User" user "User.Comments")
		(21 "Eco1.User" user "User.Eco1")
		(23 "Eco2.User" user "User.Eco2")
		(25 "Edge.Cuts" user "Board Geometry/Outline")
		(27 "Margin" user)
		(31 "F.CrtYd" user "Package Geometry/Place Bound Top")
		(29 "B.CrtYd" user "Package Geometry/Place Bound Bottom")
		(35 "F.Fab" user "Ref Des/Assembly Top")
		(33 "B.Fab" user "Ref Des/Assembly Bottom")
	)
	(footprint ""
		(layer "B.Cu")
		(at 137.972038 -163.812474)
		(property "Reference" "C905"
			(at 0.758952 1.266444 0)
			(unlocked yes)
			(layer "B.SilkS")
			(effects
				(font
					(size 0.7874 0.5842)
					(thickness 0.1524)
				)
				(justify left mirror)
			)
		)
		(property "Value" ""
			(at 0 0 0)
			(layer "B.Fab")
			(effects
				(font
					(size 1.27 1.27)
				)
				(justify mirror)
			)
		)
		(duplicate_pad_numbers_are_jumpers no)
		(fp_line
			(start -0.7874 -0.4064)
			(end -0.7874 0.4064)
			(stroke
				(width 0.1524)
				(type default)
			)
			(layer "B.SilkS")
		)
		(fp_line
			(start -0.7874 0.4064)
			(end 0.7874 0.4064)
			(stroke
				(width 0.1524)
				(type default)
			)
			(layer "B.SilkS")
		)
		(fp_line
			(start 0 0.381)
			(end 0 -0.381)
			(stroke
				(width 0.1524)
				(type default)
			)
			(layer "B.SilkS")
		)
		(fp_line
			(start 0.7874 -0.4064)
			(end -0.7874 -0.4064)
			(stroke
				(width 0.1524)
				(type default)
			)
			(layer "B.SilkS")
		)
		(fp_line
			(start 0.7874 0.4064)
			(end 0.7874 -0.4064)
			(stroke
				(width 0.1524)
				(type default)
			)
			(layer "B.SilkS")
		)
		(fp_poly
			(pts
				(xy 0.5334 0.254) (xy 0.635 0.254) (xy 0.635 0.2286) (xy 0.635 -0.254) (xy 0.5334 -0.254) (xy 0.5334 -0.2794)
				(xy -0.5334 -0.2794) (xy -0.5334 -0.254) (xy -0.635 -0.254) (xy -0.635 0.254) (xy -0.5334 0.254)
				(xy -0.5334 0.2794) (xy 0.508 0.2794) (xy 0.5334 0.2794)
			)
			(stroke
				(width 0)
				(type default)
			)
			(fill no)
			(layer "B.CrtYd")
		)
		(pad "1" smd rect
			(at -0.40005 0 180)
			(size 0.4572 0.508)
			(layers "B.Cu" "B.Mask" "B.Paste")
			(net "P3V3_NODE1")
		)
		(pad "2" smd rect
			(at 0.40005 0 180)
			(size 0.4572 0.508)
			(layers "B.Cu" "B.Mask" "B.Paste")
			(net "GND")
		)
	)
	(footprint ""
		(layer "B.Cu")
		(at 173.600872 -159.346138 -90)
		(property "Reference" "C521"
			(at -2.549398 0.127254 270)
			(unlocked yes)
			(layer "B.SilkS")
			(effects
				(font
					(size 0.7874 0.5842)
					(thickness 0.1524)
				)
				(justify left mirror)
			)
		)
		(property "Value" ""
			(at 0 0 90)
			(layer "B.Fab")
			(effects
				(font
					(size 1.27 1.27)
				)
				(justify mirror)
			)
		)
		(duplicate_pad_numbers_are_jumpers no)
		(fp_line
			(start -0.7874 0.4064)
			(end 0.7874 0.4064)
			(stroke
				(width 0.1524)
				(type default)
			)
			(layer "B.SilkS")
		)
		(fp_line
			(start 0.7874 0.4064)
			(end 0.7874 -0.4064)
			(stroke
				(width 0.1524)
				(type default)
			)
			(layer "B.SilkS")
		)
		(fp_line
			(start 0 0.381)
			(end 0 -0.381)
			(stroke
				(width 0.1524)
				(type default)
			)
			(layer "B.SilkS")
		)
		(fp_line
			(start -0.7874 -0.4064)
			(end -0.7874 0.4064)
			(stroke
				(width 0.1524)
				(type default)
			)
			(layer "B.SilkS")
		)
		(fp_line
			(start 0.7874 -0.4064)
			(end -0.7874 -0.4064)
			(stroke
				(width 0.1524)
				(type default)
			)
			(layer "B.SilkS")
		)
		(fp_poly
			(pts
				(xy 0.5334 0.254) (xy 0.635 0.254) (xy 0.635 0.2286) (xy 0.635 -0.254) (xy 0.5334 -0.254) (xy 0.5334 -0.2794)
				(xy -0.5334 -0.2794) (xy -0.5334 -0.254) (xy -0.635 -0.254) (xy -0.635 0.254) (xy -0.5334 0.254)
				(xy -0.5334 0.2794) (xy 0.508 0.2794) (xy 0.5334 0.2794)
			)
			(stroke
				(width 0)
				(type default)
			)
			(fill no)
			(layer "B.CrtYd")
		)
		(pad "1" smd rect
			(at -0.40005 0 90)
			(size 0.4572 0.508)
			(layers "B.Cu" "B.Mask" "B.Paste")
			(net "P1V9_LAN2")
		)
		(pad "2" smd rect
			(at 0.40005 0 90)
			(size 0.4572 0.508)
			(layers "B.Cu" "B.Mask" "B.Paste")
			(net "GND")
		)
	)
	(footprint ""
		(layer "B.Cu")
		(at 50.278538 -79.658718 180)
		(property "Reference" "C99"
			(at 14.413738 -31.336234 0)
			(unlocked yes)
			(layer "B.SilkS")
			(effects
				(font
					(size 0.7874 0.5842)
					(thickness 0.1524)
				)
				(justify left mirror)
			)
		)
		(property "Value" ""
			(at 0 0 0)
			(layer "B.Fab")
			(effects
				(font
					(size 1.27 1.27)
				)
				(justify mirror)
			)
		)
		(duplicate_pad_numbers_are_jumpers no)
		(fp_line
			(start 0.7874 0.4064)
			(end 0.7874 -0.4064)
			(stroke
				(width 0.1524)
				(type default)
			)
			(layer "B.SilkS")
		)
		(fp_line
			(start 0.7874 -0.4064)
			(end -0.7874 -0.4064)
			(stroke
				(width 0.1524)
				(type default)
			)
			(layer "B.SilkS")
		)
		(fp_line
			(start 0 0.381)
			(end 0 -0.381)
			(stroke
				(width 0.1524)
				(type default)
			)
			(layer "B.SilkS")
		)
		(fp_line
			(start -0.7874 0.4064)
			(end 0.7874 0.4064)
			(stroke
				(width 0.1524)
				(type default)
			)
			(layer "B.SilkS")
		)
		(fp_line
			(start -0.7874 -0.4064)
			(end -0.7874 0.4064)
			(stroke
				(width 0.1524)
				(type default)
			)
			(layer "B.SilkS")
		)
		(fp_poly
			(pts
				(xy 0.5334 0.254) (xy 0.635 0.254) (xy 0.635 0.2286) (xy 0.635 -0.254) (xy 0.5334 -0.254) (xy 0.5334 -0.2794)
				(xy -0.5334 -0.2794) (xy -0.5334 -0.254) (xy -0.635 -0.254) (xy -0.635 0.254) (xy -0.5334 0.254)
				(xy -0.5334 0.2794) (xy 0.508 0.2794) (xy 0.5334 0.2794)
			)
			(stroke
				(width 0)
				(type default)
			)
			(fill no)
			(layer "B.CrtYd")
		)
		(pad "1" smd rect
			(at -0.40005 0)
			(size 0.4572 0.508)
			(layers "B.Cu" "B.Mask" "B.Paste")
			(net "P1V05_NODE1")
		)
		(pad "2" smd rect
			(at 0.40005 0)
			(size 0.4572 0.508)
			(layers "B.Cu" "B.Mask" "B.Paste")
			(net "GND")
		)
	)
	(footprint ""
		(layer "B.Cu")
		(at 55.592218 -132.756402 -90)
		(property "Reference" "C205"
			(at -1.982978 0.008128 270)
			(unlocked yes)
			(layer "B.SilkS")
			(effects
				(font
					(size 0.7874 0.5842)
					(thickness 0.1524)
				)
				(justify left mirror)
			)
		)
		(property "Value" ""
			(at 0 0 90)
			(layer "B.Fab")
			(effects
				(font
					(size 1.27 1.27)
				)
				(justify mirror)
			)
		)
		(duplicate_pad_numbers_are_jumpers no)
		(fp_line
			(start -0.7874 0.4064)
			(end 0.7874 0.4064)
			(stroke
				(width 0.1524)
				(type default)
			)
			(layer "B.SilkS")
		)
		(fp_line
			(start 0.7874 0.4064)
			(end 0.7874 -0.4064)
			(stroke
				(width 0.1524)
				(type default)
			)
			(layer "B.SilkS")
		)
		(fp_line
			(start 0 0.381)
			(end 0 -0.381)
			(stroke
				(width 0.1524)
				(type default)
			)
			(layer "B.SilkS")
		)
		(fp_line
			(start -0.7874 -0.4064)
			(end -0.7874 0.4064)
			(stroke
				(width 0.1524)
				(type default)
			)
			(layer "B.SilkS")
		)
		(fp_line
			(start 0.7874 -0.4064)
			(end -0.7874 -0.4064)
			(stroke
				(width 0.1524)
				(type default)
			)
			(layer "B.SilkS")
		)
		(fp_poly
			(pts
				(xy 0.5334 0.254) (xy 0.635 0.254) (xy 0.635 0.2286) (xy 0.635 -0.254) (xy 0.5334 -0.254) (xy 0.5334 -0.2794)
				(xy -0.5334 -0.2794) (xy -0.5334 -0.254) (xy -0.635 -0.254) (xy -0.635 0.254) (xy -0.5334 0.254)
				(xy -0.5334 0.2794) (xy 0.508 0.2794) (xy 0.5334 0.2794)
			)
			(stroke
				(width 0)
				(type default)
			)
			(fill no)
			(layer "B.CrtYd")
		)
		(pad "1" smd rect
			(at -0.40005 0 90)
			(size 0.4572 0.508)
			(layers "B.Cu" "B.Mask" "B.Paste")
			(net "GND")
		)
		(pad "2" smd rect
			(at 0.40005 0 90)
			(size 0.4572 0.508)
			(layers "B.Cu" "B.Mask" "B.Paste")
			(net "P0V75_BMC_VTTREF_NODE1")
		)
	)
	(footprint ""
		(layer "B.Cu")
		(at 82.04327 -21.09724 90)
		(property "Reference" "C163"
			(at -5.835904 -0.68834 270)
			(unlocked yes)
			(layer "B.SilkS")
			(effects
				(font
					(size 0.7874 0.5842)
					(thickness 0.1524)
				)
				(justify left mirror)
			)
		)
		(property "Value" ""
			(at 0 0 90)
			(layer "B.Fab")
			(effects
				(font
					(size 1.27 1.27)
				)
				(justify mirror)
			)
		)
		(duplicate_pad_numbers_are_jumpers no)
		(fp_line
			(start 0.7874 -0.4064)
			(end -0.7874 -0.4064)
			(stroke
				(width 0.1524)
				(type default)
			)
			(layer "B.SilkS")
		)
		(fp_line
			(start -0.7874 -0.4064)
			(end -0.7874 0.4064)
			(stroke
				(width 0.1524)
				(type default)
			)
			(layer "B.SilkS")
		)
		(fp_line
			(start 0 0.381)
			(end 0 -0.381)
			(stroke
				(width 0.1524)
				(type default)
			)
			(layer "B.SilkS")
		)
		(fp_line
			(start 0.7874 0.4064)
			(end 0.7874 -0.4064)
			(stroke
				(width 0.1524)
				(type default)
			)
			(layer "B.SilkS")
		)
		(fp_line
			(start -0.7874 0.4064)
			(end 0.7874 0.4064)
			(stroke
				(width 0.1524)
				(type default)
			)
			(layer "B.SilkS")
		)
		(fp_poly
			(pts
				(xy 0.5334 0.254) (xy 0.635 0.254) (xy 0.635 0.2286) (xy 0.635 -0.254) (xy 0.5334 -0.254) (xy 0.5334 -0.2794)
				(xy -0.5334 -0.2794) (xy -0.5334 -0.254) (xy -0.635 -0.254) (xy -0.635 0.254) (xy -0.5334 0.254)
				(xy -0.5334 0.2794) (xy 0.508 0.2794) (xy 0.5334 0.2794)
			)
			(stroke
				(width 0)
				(type default)
			)
			(fill no)
			(layer "B.CrtYd")
		)
		(pad "1" smd rect
			(at -0.40005 0 270)
			(size 0.4572 0.508)
			(layers "B.Cu" "B.Mask" "B.Paste")
			(net "PV_VDDR_NODE1")
		)
		(pad "2" smd rect
			(at 0.40005 0 270)
			(size 0.4572 0.508)
			(layers "B.Cu" "B.Mask" "B.Paste")
			(net "GND")
		)
	)
	(footprint ""
		(layer "B.Cu")
		(at 132.775452 -135.87095 -90)
		(property "Reference" "C873"
			(at 5.07365 -0.26797 270)
			(unlocked yes)
			(layer "B.SilkS")
			(effects
				(font
					(size 0.7874 0.5842)
					(thickness 0.1524)
				)
				(justify left mirror)
			)
		)
		(property "Value" ""
			(at 0 0 90)
			(layer "B.Fab")
			(effects
				(font
					(size 1.27 1.27)
				)
				(justify mirror)
			)
		)
		(duplicate_pad_numbers_are_jumpers no)
		(fp_line
			(start -0.7874 0.4064)
			(end 0.7874 0.4064)
			(stroke
				(width 0.1524)
				(type default)
			)
			(layer "B.SilkS")
		)
		(fp_line
			(start 0.7874 0.4064)
			(end 0.7874 -0.4064)
			(stroke
				(width 0.1524)
				(type default)
			)
			(layer "B.SilkS")
		)
		(fp_line
			(start 0 0.381)
			(end 0 -0.381)
			(stroke
				(width 0.1524)
				(type default)
			)
			(layer "B.SilkS")
		)
		(fp_line
			(start -0.7874 -0.4064)
			(end -0.7874 0.4064)
			(stroke
				(width 0.1524)
				(type default)
			)
			(layer "B.SilkS")
		)
		(fp_line
			(start 0.7874 -0.4064)
			(end -0.7874 -0.4064)
			(stroke
				(width 0.1524)
				(type default)
			)
			(layer "B.SilkS")
		)
		(fp_poly
			(pts
				(xy 0.5334 0.254) (xy 0.635 0.254) (xy 0.635 0.2286) (xy 0.635 -0.254) (xy 0.5334 -0.254) (xy 0.5334 -0.2794)
				(xy -0.5334 -0.2794) (xy -0.5334 -0.254) (xy -0.635 -0.254) (xy -0.635 0.254) (xy -0.5334 0.254)
				(xy -0.5334 0.2794) (xy 0.508 0.2794) (xy 0.5334 0.2794)
			)
			(stroke
				(width 0)
				(type default)
			)
			(fill no)
			(layer "B.CrtYd")
		)
		(pad "1" smd rect
			(at -0.40005 0 90)
			(size 0.4572 0.508)
			(layers "B.Cu" "B.Mask" "B.Paste")
			(net "P1V0_NODE1")
		)
		(pad "2" smd rect
			(at 0.40005 0 90)
			(size 0.4572 0.508)
			(layers "B.Cu" "B.Mask" "B.Paste")
			(net "GND")
		)
	)
	(footprint ""
		(layer "B.Cu")
		(at 145.65376 -187.999624 -90)
		(property "Reference" "C729"
			(at -4.438396 1.850644 270)
			(unlocked yes)
			(layer "B.SilkS")
			(effects
				(font
					(size 0.7874 0.5842)
					(thickness 0.1524)
				)
				(justify left mirror)
			)
		)
		(property "Value" ""
			(at 0 0 90)
			(layer "B.Fab")
			(effects
				(font
					(size 1.27 1.27)
				)
				(justify mirror)
			)
		)
		(duplicate_pad_numbers_are_jumpers no)
		(fp_line
			(start -0.7874 0.4064)
			(end 0.7874 0.4064)
			(stroke
				(width 0.1524)
				(type default)
			)
			(layer "B.SilkS")
		)
		(fp_line
			(start 0.7874 0.4064)
			(end 0.7874 -0.4064)
			(stroke
				(width 0.1524)
				(type default)
			)
			(layer "B.SilkS")
		)
		(fp_line
			(start 0 0.381)
			(end 0 -0.381)
			(stroke
				(width 0.1524)
				(type default)
			)
			(layer "B.SilkS")
		)
		(fp_line
			(start -0.7874 -0.4064)
			(end -0.7874 0.4064)
			(stroke
				(width 0.1524)
				(type default)
			)
			(layer "B.SilkS")
		)
		(fp_line
			(start 0.7874 -0.4064)
			(end -0.7874 -0.4064)
			(stroke
				(width 0.1524)
				(type default)
			)
			(layer "B.SilkS")
		)
		(fp_poly
			(pts
				(xy 0.5334 0.254) (xy 0.635 0.254) (xy 0.635 0.2286) (xy 0.635 -0.254) (xy 0.5334 -0.254) (xy 0.5334 -0.2794)
				(xy -0.5334 -0.2794) (xy -0.5334 -0.254) (xy -0.635 -0.254) (xy -0.635 0.254) (xy -0.5334 0.254)
				(xy -0.5334 0.2794) (xy 0.508 0.2794) (xy 0.5334 0.2794)
			)
			(stroke
				(width 0)
				(type default)
			)
			(fill no)
			(layer "B.CrtYd")
		)
		(pad "1" smd rect
			(at -0.40005 0 90)
			(size 0.4572 0.508)
			(layers "B.Cu" "B.Mask" "B.Paste")
			(net "UART_T11_NODE2_TXD_R")
		)
		(pad "2" smd rect
			(at 0.40005 0 90)
			(size 0.4572 0.508)
			(layers "B.Cu" "B.Mask" "B.Paste")
			(net "GND")
		)
	)
	(footprint ""
		(layer "B.Cu")
		(at 41.58869 -96.994726 -90)
		(property "Reference" "R122"
			(at -1.09347 0.02032 270)
			(unlocked yes)
			(layer "B.SilkS")
			(effects
				(font
					(size 0.7874 0.5842)
					(thickness 0.1524)
				)
				(justify left mirror)
			)
		)
		(property "Value" ""
			(at 0 0 90)
			(layer "B.Fab")
			(effects
				(font
					(size 1.27 1.27)
				)
				(justify mirror)
			)
		)
		(duplicate_pad_numbers_are_jumpers no)
		(fp_line
			(start -0.7874 0.4064)
			(end 0.7874 0.4064)
			(stroke
				(width 0.1524)
				(type default)
			)
			(layer "B.SilkS")
		)
		(fp_line
			(start 0.7874 0.4064)
			(end 0.7874 -0.4064)
			(stroke
				(width 0.1524)
				(type default)
			)
			(layer "B.SilkS")
		)
		(fp_line
			(start -0.7874 -0.4064)
			(end -0.7874 0.4064)
			(stroke
				(width 0.1524)
				(type default)
			)
			(layer "B.SilkS")
		)
		(fp_line
			(start 0.7874 -0.4064)
			(end -0.7874 -0.4064)
			(stroke
				(width 0.1524)
				(type default)
			)
			(layer "B.SilkS")
		)
		(fp_poly
			(pts
				(xy 0.508 0.2794) (xy 0.508 0.2286) (xy 0.635 0.2286) (xy 0.635 -0.254) (xy 0.5334 -0.254) (xy 0.5334 -0.2794)
				(xy -0.5334 -0.2794) (xy -0.5334 -0.254) (xy -0.635 -0.254) (xy -0.635 0.254) (xy -0.5334 0.254)
				(xy -0.5334 0.2794)
			)
			(stroke
				(width 0)
				(type default)
			)
			(fill no)
			(layer "B.CrtYd")
		)
		(pad "1" smd rect
			(at -0.40005 0 90)
			(size 0.4572 0.508)
			(layers "B.Cu" "B.Mask" "B.Paste")
			(net "P3V3_NODE1")
		)
		(pad "2" smd rect
			(at 0.40005 0 90)
			(size 0.4572 0.508)
			(layers "B.Cu" "B.Mask" "B.Paste")
			(net "SMB_CPU_NODE1_XDP_CLK")
		)
	)
	(footprint ""
		(layer "B.Cu")
		(at 173.54042 -116.280946 -90)
		(property "Reference" "C793"
			(at 3.061208 -0.771906 270)
			(unlocked yes)
			(layer "B.SilkS")
			(effects
				(font
					(size 0.7874 0.5842)
					(thickness 0.1524)
				)
				(justify mirror)
			)
		)
		(property "Value" ""
			(at 0 0 90)
			(layer "B.Fab")
			(effects
				(font
					(size 1.27 1.27)
				)
				(justify mirror)
			)
		)
		(duplicate_pad_numbers_are_jumpers no)
		(fp_line
			(start -1.2954 0.5842)
			(end 1.2954 0.5842)
			(stroke
				(width 0.1524)
				(type default)
			)
			(layer "B.SilkS")
		)
		(fp_line
			(start 1.2954 0.5842)
			(end 1.2954 -0.5842)
			(stroke
				(width 0.1524)
				(type default)
			)
			(layer "B.SilkS")
		)
		(fp_line
			(start -1.2954 -0.5842)
			(end -1.2954 0.5842)
			(stroke
				(width 0.1524)
				(type default)
			)
			(layer "B.SilkS")
		)
		(fp_line
			(start 0 -0.5842)
			(end 0 0.5842)
			(stroke
				(width 0.1524)
				(type default)
			)
			(layer "B.SilkS")
		)
		(fp_line
			(start 1.2954 -0.5842)
			(end -1.2954 -0.5842)
			(stroke
				(width 0.1524)
				(type default)
			)
			(layer "B.SilkS")
		)
		(fp_poly
			(pts
				(xy -0.8636 -0.4572) (xy -0.8636 -0.3556) (xy -1.143 -0.3556) (xy -1.143 0.3556) (xy -0.8636 0.3556)
				(xy -0.8636 0.4572) (xy 0.8636 0.4572) (xy 0.8636 0.3556) (xy 1.143 0.3556) (xy 1.143 -0.3556) (xy 0.8636 -0.3556)
				(xy 0.8636 -0.4572)
			)
			(stroke
				(width 0)
				(type default)
			)
			(fill no)
			(layer "B.CrtYd")
		)
		(fp_line
			(start -0.884936 0.504952)
			(end 0.884936 0.504952)
			(stroke
				(width 0.1)
				(type default)
			)
			(layer "B.Fab")
		)
		(fp_line
			(start 0.884936 0.504952)
			(end 0.884936 -0.504952)
			(stroke
				(width 0.1)
				(type default)
			)
			(layer "B.Fab")
		)
		(fp_line
			(start -0.884936 -0.504952)
			(end -0.884936 0.504952)
			(stroke
				(width 0.1)
				(type default)
			)
			(layer "B.Fab")
		)
		(fp_line
			(start 0.884936 -0.504952)
			(end -0.884936 -0.504952)
			(stroke
				(width 0.1)
				(type default)
			)
			(layer "B.Fab")
		)
		(pad "1" smd rect
			(at -0.7366 0)
			(size 0.7112 0.8128)
			(layers "B.Cu" "B.Mask" "B.Paste")
			(net "P3V3_STB_NODE1")
		)
		(pad "2" smd rect
			(at 0.7366 0)
			(size 0.7112 0.8128)
			(layers "B.Cu" "B.Mask" "B.Paste")
			(net "GND")
		)
	)
	(footprint ""
		(layer "B.Cu")
		(at 137.970006 -38.45941 180)
		(property "Reference" "R1179"
			(at 4.172458 -18.307812 0)
			(unlocked yes)
			(layer "B.SilkS")
			(effects
				(font
					(size 0.7874 0.5842)
					(thickness 0.1524)
				)
				(justify left mirror)
			)
		)
		(property "Value" ""
			(at 0 0 0)
			(layer "B.Fab")
			(effects
				(font
					(size 1.27 1.27)
				)
				(justify mirror)
			)
		)
		(duplicate_pad_numbers_are_jumpers no)
		(fp_line
			(start 0.7874 0.4064)
			(end 0.7874 -0.4064)
			(stroke
				(width 0.1524)
				(type default)
			)
			(layer "B.SilkS")
		)
		(fp_line
			(start 0.7874 -0.4064)
			(end -0.7874 -0.4064)
			(stroke
				(width 0.1524)
				(type default)
			)
			(layer "B.SilkS")
		)
		(fp_line
			(start -0.7874 0.4064)
			(end 0.7874 0.4064)
			(stroke
				(width 0.1524)
				(type default)
			)
			(layer "B.SilkS")
		)
		(fp_line
			(start -0.7874 -0.4064)
			(end -0.7874 0.4064)
			(stroke
				(width 0.1524)
				(type default)
			)
			(layer "B.SilkS")
		)
		(fp_poly
			(pts
				(xy 0.508 0.2794) (xy 0.508 0.2286) (xy 0.635 0.2286) (xy 0.635 -0.254) (xy 0.5334 -0.254) (xy 0.5334 -0.2794)
				(xy -0.5334 -0.2794) (xy -0.5334 -0.254) (xy -0.635 -0.254) (xy -0.635 0.254) (xy -0.5334 0.254)
				(xy -0.5334 0.2794)
			)
			(stroke
				(width 0)
				(type default)
			)
			(fill no)
			(layer "B.CrtYd")
		)
		(pad "1" smd rect
			(at -0.40005 0)
			(size 0.4572 0.508)
			(layers "B.Cu" "B.Mask" "B.Paste")
			(net "CPLD_WDT3_R")
		)
		(pad "2" smd rect
			(at 0.40005 0)
			(size 0.4572 0.508)
			(layers "B.Cu" "B.Mask" "B.Paste")
			(net "CPLD_WDT3")
		)
	)
)
